(kicad_pcb
	(version 20260206)
	(generator "pcbnew")
	(generator_version "10.0")
	(general
		(thickness 1.6)
		(legacy_teardrops no)
	)
	(paper "A4")
	(title_block
		(title "Bryce Canyon_R.DPB_16317-1_OCP.brd")
		(comment 1 "Bryce Canyon / footprints 905-908 of 2099")
	)
	(layers
		(0 "F.Cu" signal "TOP")
		(4 "In1.Cu" signal "L2GND")
		(6 "In2.Cu" signal "L3")
		(8 "In3.Cu" signal "L4VCC")
		(10 "In4.Cu" signal "L5VCC")
		(12 "In5.Cu" signal "L6")
		(14 "In6.Cu" signal "L7GND")
		(2 "B.Cu" signal "BOTTOM")
		(9 "F.Adhes" user "F.Adhesive")
		(11 "B.Adhes" user "B.Adhesive")
		(13 "F.Paste" user "Package Geometry/Pastemask Top")
		(15 "B.Paste" user "Package Geometry/Pastemask Bottom")
		(5 "F.SilkS" user "Ref Des/Silkscreen Top")
		(7 "B.SilkS" user "Ref Des/Silkscreen Bottom")
		(1 "F.Mask" user "Board Geometry/Soldermask Top")
		(3 "B.Mask" user "Board Geometry/Soldermask Bottom")
		(17 "Dwgs.User" user "User.Drawings")
		(19 "Cmts.User" user "User.Comments")
		(21 "Eco1.User" user "User.Eco1")
		(23 "Eco2.User" user "User.Eco2")
		(25 "Edge.Cuts" user "Board Geometry/Outline")
		(27 "Margin" user)
		(31 "F.CrtYd" user "Package Geometry/Place Bound Top")
		(29 "B.CrtYd" user "Package Geometry/Place Bound Bottom")
		(35 "F.Fab" user "Ref Des/Assembly Top")
		(33 "B.Fab" user "Ref Des/Assembly Bottom")
	)
	(footprint ""
		(layer "F.Cu")
		(at 420.200074 -258.910074 -90)
		(property "Reference" "HDDSAS9"
			(at 0 0 270)
			(layer "F.SilkS")
			(hide yes)
			(effects
				(font
					(size 1.27 1.27)
				)
			)
		)
		(property "Value" "SKT-SAS15P-14P-45-GP"
			(at -20.7645 -8.9789 270)
			(unlocked yes)
			(layer "F.Fab")
			(hide yes)
			(effects
				(font
					(size 1.016 1.016)
					(thickness 0.1524)
				)
			)
		)
		(property "Device Type" "10120818-001C-TRLF"
			(at -20.7645 -10.5029 270)
			(unlocked yes)
			(layer "F.Fab")
			(hide yes)
			(effects
				(font
					(size 1.016 1.016)
					(thickness 0.1524)
				)
			)
		)
		(duplicate_pad_numbers_are_jumpers no)
		(fp_line
			(start 1.651 4.2926)
			(end 1.651 3.0099)
			(stroke
				(width 0.1524)
				(type default)
			)
			(layer "F.SilkS")
		)
		(fp_line
			(start 8.509 4.2926)
			(end 1.651 4.2926)
			(stroke
				(width 0.1524)
				(type default)
			)
			(layer "F.SilkS")
		)
		(fp_line
			(start -23.4188 3.0099)
			(end -23.4188 -3.2512)
			(stroke
				(width 0.1524)
				(type default)
			)
			(layer "F.SilkS")
		)
		(fp_line
			(start 1.651 3.0099)
			(end -23.4188 3.0099)
			(stroke
				(width 0.1524)
				(type default)
			)
			(layer "F.SilkS")
		)
		(fp_line
			(start 8.509 3.0099)
			(end 8.509 4.2926)
			(stroke
				(width 0.1524)
				(type default)
			)
			(layer "F.SilkS")
		)
		(fp_line
			(start 23.4188 3.0099)
			(end 8.509 3.0099)
			(stroke
				(width 0.1524)
				(type default)
			)
			(layer "F.SilkS")
		)
		(fp_line
			(start -23.4188 -3.2512)
			(end 23.4188 -3.2512)
			(stroke
				(width 0.1524)
				(type default)
			)
			(layer "F.SilkS")
		)
		(fp_line
			(start 23.4188 -3.2512)
			(end 23.4188 3.0099)
			(stroke
				(width 0.1524)
				(type default)
			)
			(layer "F.SilkS")
		)
		(fp_line
			(start 15.5067 -3.3401)
			(end 16.2687 -3.3401)
			(stroke
				(width 0.3302)
				(type default)
			)
			(layer "F.SilkS")
		)
		(fp_poly
			(pts
				(xy 15.868904 -3.230372) (xy 16.503904 -3.865372) (xy 15.233904 -3.865372)
			)
			(stroke
				(width 0)
				(type default)
			)
			(fill yes)
			(layer "F.SilkS")
		)
		(fp_poly
			(pts
				(xy -22.8727 -2.7559) (xy 22.8727 -2.7559) (xy 22.8727 2.7559) (xy 8.255 2.7559) (xy 8.255 3.5179)
				(xy 1.905 3.5179) (xy 1.905 2.7559) (xy -22.8727 2.7559)
			)
			(stroke
				(width 0)
				(type default)
			)
			(fill no)
			(layer "F.CrtYd")
		)
		(fp_poly
			(pts
				(xy 1.397 4.5466) (xy 1.397 3.2639) (xy -23.6728 3.2639) (xy -23.6728 -3.5052) (xy 23.6728 -3.5052)
				(xy 23.6728 -0.00635) (xy 22.8727 -0.00635) (xy 22.8727 -2.7559) (xy -22.8727 -2.7559) (xy -22.8727 2.7559)
				(xy 1.905 2.7559) (xy 1.905 3.5179) (xy 8.255 3.5179) (xy 8.255 2.7559) (xy 22.8727 2.7559) (xy 22.8727 0.00635)
				(xy 23.6728 0.00635) (xy 23.6728 3.2639) (xy 8.763 3.2639) (xy 8.763 4.5466)
			)
			(stroke
				(width 0)
				(type default)
			)
			(fill no)
			(layer "F.CrtYd")
		)
		(fp_poly
			(pts
				(xy 1.397 4.5466) (xy 1.397 3.2639) (xy -23.6728 3.2639) (xy -23.6728 -3.5052) (xy 23.6728 -3.5052)
				(xy 23.6728 3.2639) (xy 8.763 3.2639) (xy 8.763 4.5466)
			)
			(stroke
				(width 0)
				(type default)
			)
			(fill no)
			(layer "F.Fab")
		)
		(pad "" np_thru_hole circle
			(at -18.874994 0 270)
			(size 0.254 0.254)
			(drill 1.3462)
			(layers "*.Cu" "*.Mask")
			(clearance 0.9017)
			(thermal_gap 0.9017)
		)
		(pad "" np_thru_hole circle
			(at 18.874994 0 270)
			(size 0.254 0.254)
			(drill 0.9398)
			(layers "*.Cu" "*.Mask")
			(clearance 0.6985)
			(thermal_gap 0.6985)
		)
		(pad "G1" smd rect
			(at 21.874988 0 270)
			(size 2.5908 2.5908)
			(layers "F.Cu" "F.Mask" "F.Paste")
			(net "GND")
		)
		(pad "G2" smd rect
			(at -21.874988 0 270)
			(size 2.5908 2.5908)
			(layers "F.Cu" "F.Mask" "F.Paste")
			(net "GND")
		)
		(pad "P1" smd rect
			(at 1.905 -1.82499 270)
			(size 0.6096 2.3622)
			(layers "F.Cu" "F.Mask" "F.Paste")
			(net "Net_1759")
		)
		(pad "P2" smd rect
			(at 0.635 -1.82499 270)
			(size 0.6096 2.3622)
			(layers "F.Cu" "F.Mask" "F.Paste")
			(net "Net_1760")
		)
		(pad "P3" smd rect
			(at -0.635 -1.82499 270)
			(size 0.6096 2.3622)
			(layers "F.Cu" "F.Mask" "F.Paste")
			(net "Net_1761")
		)
		(pad "P4" smd rect
			(at -1.905 -1.82499 270)
			(size 0.6096 2.3622)
			(layers "F.Cu" "F.Mask" "F.Paste")
			(net "GND")
		)
		(pad "P5" smd rect
			(at -3.175 -1.82499 270)
			(size 0.6096 2.3622)
			(layers "F.Cu" "F.Mask" "F.Paste")
			(net "HDD_PRSNT_9")
		)
		(pad "P6" smd rect
			(at -4.445 -1.82499 270)
			(size 0.6096 2.3622)
			(layers "F.Cu" "F.Mask" "F.Paste")
			(net "GND")
		)
		(pad "P7" smd rect
			(at -5.715 -1.82499 270)
			(size 0.6096 2.3622)
			(layers "F.Cu" "F.Mask" "F.Paste")
			(net "5V_PRE_9")
		)
		(pad "P8" smd rect
			(at -6.985 -1.82499 270)
			(size 0.6096 2.3622)
			(layers "F.Cu" "F.Mask" "F.Paste")
			(net "P5V_HDD9")
		)
		(pad "P9" smd rect
			(at -8.255 -1.82499 270)
			(size 0.6096 2.3622)
			(layers "F.Cu" "F.Mask" "F.Paste")
			(net "P5V_HDD9")
		)
		(pad "P10" smd rect
			(at -9.525 -1.82499 270)
			(size 0.6096 2.3622)
			(layers "F.Cu" "F.Mask" "F.Paste")
			(net "GND")
		)
		(pad "P11" smd rect
			(at -10.795 -1.82499 270)
			(size 0.6096 2.3622)
			(layers "F.Cu" "F.Mask" "F.Paste")
			(net "ACT_HDD_9")
		)
		(pad "P12" smd rect
			(at -12.065 -1.82499 270)
			(size 0.6096 2.3622)
			(layers "F.Cu" "F.Mask" "F.Paste")
			(net "GND")
		)
		(pad "P13" smd rect
			(at -13.335 -1.82499 270)
			(size 0.6096 2.3622)
			(layers "F.Cu" "F.Mask" "F.Paste")
			(net "12V_PRE_9")
		)
		(pad "P14" smd rect
			(at -14.605 -1.82499 270)
			(size 0.6096 2.3622)
			(layers "F.Cu" "F.Mask" "F.Paste")
			(net "P12V_HDD9")
		)
		(pad "P15" smd rect
			(at -15.875 -1.82499 270)
			(size 0.6096 2.3622)
			(layers "F.Cu" "F.Mask" "F.Paste")
			(net "P12V_HDD9")
		)
		(pad "S1" smd rect
			(at 15.875 -1.82499 270)
			(size 0.6096 2.3622)
			(layers "F.Cu" "F.Mask" "F.Paste")
			(net "GND")
		)
		(pad "S2" smd rect
			(at 14.605 -1.82499 270)
			(size 0.6096 2.3622)
			(layers "F.Cu" "F.Mask" "F.Paste")
			(net "SAS_HDD_RX_P9")
		)
		(pad "S3" smd rect
			(at 13.335 -1.82499 270)
			(size 0.6096 2.3622)
			(layers "F.Cu" "F.Mask" "F.Paste")
			(net "SAS_HDD_RX_N9")
		)
		(pad "S4" smd rect
			(at 12.065 -1.82499 270)
			(size 0.6096 2.3622)
			(layers "F.Cu" "F.Mask" "F.Paste")
			(net "GND")
		)
		(pad "S5" smd rect
			(at 10.795 -1.82499 270)
			(size 0.6096 2.3622)
			(layers "F.Cu" "F.Mask" "F.Paste")
			(net "PHY_DRV_B_TO_SCC_B_9_DN")
		)
		(pad "S6" smd rect
			(at 9.525 -1.82499 270)
			(size 0.6096 2.3622)
			(layers "F.Cu" "F.Mask" "F.Paste")
			(net "PHY_DRV_B_TO_SCC_B_9_DP")
		)
		(pad "S7" smd rect
			(at 8.255 -1.82499 270)
			(size 0.6096 2.3622)
			(layers "F.Cu" "F.Mask" "F.Paste")
			(net "GND")
		)
		(pad "S8" smd rect
			(at 7.480046 2.845054 270)
			(size 0.508 2.3622)
			(layers "F.Cu" "F.Mask" "F.Paste")
			(net "GND")
		)
		(pad "S9" smd rect
			(at 6.679946 2.845054 270)
			(size 0.508 2.3622)
			(layers "F.Cu" "F.Mask" "F.Paste")
			(net "Net_432")
		)
		(pad "S10" smd rect
			(at 5.8801 2.845054 270)
			(size 0.508 2.3622)
			(layers "F.Cu" "F.Mask" "F.Paste")
			(net "Net_324")
		)
		(pad "S11" smd rect
			(at 5.08 2.845054 270)
			(size 0.508 2.3622)
			(layers "F.Cu" "F.Mask" "F.Paste")
			(net "GND")
		)
		(pad "S12" smd rect
			(at 4.2799 2.845054 270)
			(size 0.508 2.3622)
			(layers "F.Cu" "F.Mask" "F.Paste")
			(net "Net_360")
		)
		(pad "S13" smd rect
			(at 3.480054 2.845054 270)
			(size 0.508 2.3622)
			(layers "F.Cu" "F.Mask" "F.Paste")
			(net "Net_396")
		)
		(pad "S14" smd rect
			(at 2.679954 2.845054 270)
			(size 0.508 2.3622)
			(layers "F.Cu" "F.Mask" "F.Paste")
			(net "GND")
		)
		(zone
			(layer "F.Cu")
			(hatch none 0.5)
			(connect_pads
				(clearance 0)
			)
			(min_thickness 0.25)
			(keepout
				(tracks allowed)
				(vias not_allowed)
				(pads allowed)
				(copperpour not_allowed)
				(footprints allowed)
			)
			(placement
				(enabled no)
				(sheetname "")
			)
			(fill
				(thermal_gap 0.5)
				(thermal_bridge_width 0.5)
				(island_removal_mode 0)
			)
			(polygon
				(pts
					(xy 423.857674 -275.648674) (xy 416.783774 -275.648674) (xy 416.783774 -282.582874) (xy 417.888674 -282.582874)
					(xy 417.888674 -278.468074) (xy 422.511474 -278.468074) (xy 422.511474 -282.582874) (xy 423.857674 -282.582874)
				)
			)
		)
		(zone
			(layer "F.Cu")
			(hatch none 0.5)
			(connect_pads
				(clearance 0)
			)
			(min_thickness 0.25)
			(keepout
				(tracks not_allowed)
				(vias allowed)
				(pads allowed)
				(copperpour not_allowed)
				(footprints allowed)
			)
			(placement
				(enabled no)
				(sheetname "")
			)
			(fill
				(thermal_gap 0.5)
				(thermal_bridge_width 0.5)
				(island_removal_mode 0)
			)
			(polygon
				(pts
					(xy 423.857674 -275.648674) (xy 416.783774 -275.648674) (xy 416.783774 -282.582874) (xy 417.888674 -282.582874)
					(xy 417.888674 -278.468074) (xy 422.511474 -278.468074) (xy 422.511474 -282.582874) (xy 423.857674 -282.582874)
				)
			)
		)
		(zone
			(layer "F.Cu")
			(hatch none 0.5)
			(connect_pads
				(clearance 0)
			)
			(min_thickness 0.25)
			(keepout
				(tracks allowed)
				(vias not_allowed)
				(pads allowed)
				(copperpour not_allowed)
				(footprints allowed)
			)
			(placement
				(enabled no)
				(sheetname "")
			)
			(fill
				(thermal_gap 0.5)
				(thermal_bridge_width 0.5)
				(island_removal_mode 0)
			)
			(polygon
				(pts
					(xy 423.857674 -242.171474) (xy 416.783774 -242.171474) (xy 416.783774 -235.237274) (xy 417.888674 -235.237274)
					(xy 417.888674 -239.352074) (xy 422.511474 -239.352074) (xy 422.511474 -235.237274) (xy 423.857674 -235.237274)
				)
			)
		)
		(zone
			(layer "F.Cu")
			(hatch none 0.5)
			(connect_pads
				(clearance 0)
			)
			(min_thickness 0.25)
			(keepout
				(tracks not_allowed)
				(vias allowed)
				(pads allowed)
				(copperpour not_allowed)
				(footprints allowed)
			)
			(placement
				(enabled no)
				(sheetname "")
			)
			(fill
				(thermal_gap 0.5)
				(thermal_bridge_width 0.5)
				(island_removal_mode 0)
			)
			(polygon
				(pts
					(xy 423.857674 -242.171474) (xy 416.783774 -242.171474) (xy 416.783774 -235.237274) (xy 417.888674 -235.237274)
					(xy 417.888674 -239.352074) (xy 422.511474 -239.352074) (xy 422.511474 -235.237274) (xy 423.857674 -235.237274)
				)
			)
		)
		(zone
			(layers "F.Cu" "B.Cu" "In1.Cu" "In2.Cu" "In3.Cu" "In4.Cu" "In5.Cu" "In6.Cu")
			(hatch none 0.5)
			(connect_pads
				(clearance 0)
			)
			(min_thickness 0.25)
			(keepout
				(tracks not_allowed)
				(vias allowed)
				(pads allowed)
				(copperpour not_allowed)
				(footprints allowed)
			)
			(placement
				(enabled no)
				(sheetname "")
			)
			(fill
				(thermal_gap 0.5)
				(thermal_bridge_width 0.5)
				(island_removal_mode 0)
			)
			(polygon
				(pts
					(arc
						(start 420.974774 -240.03508)
						(mid 419.425374 -240.03508)
						(end 420.974774 -240.03508)
					)
				)
			)
		)
		(zone
			(layers "F.Cu" "B.Cu" "In1.Cu" "In2.Cu" "In3.Cu" "In4.Cu" "In5.Cu" "In6.Cu")
			(hatch none 0.5)
			(connect_pads
				(clearance 0)
			)
			(min_thickness 0.25)
			(keepout
				(tracks not_allowed)
				(vias allowed)
				(pads allowed)
				(copperpour not_allowed)
				(footprints allowed)
			)
			(placement
				(enabled no)
				(sheetname "")
			)
			(fill
				(thermal_gap 0.5)
				(thermal_bridge_width 0.5)
				(island_removal_mode 0)
			)
			(polygon
				(pts
					(arc
						(start 421.177974 -277.785068)
						(mid 419.222174 -277.785068)
						(end 421.177974 -277.785068)
					)
				)
			)
		)
	)
	(footprint ""
		(layer "F.Cu")
		(at 481.066602 -17.4371)
		(property "Reference" "VIA72"
			(at 0 0 0)
			(layer "F.SilkS")
			(hide yes)
			(effects
				(font
					(size 1.27 1.27)
				)
			)
		)
		(property "Value" "100OHM-8L-2D36MM-L16-GP"
			(at -3.4036 -0.4572 0)
			(unlocked yes)
			(layer "F.Fab")
			(hide yes)
			(effects
				(font
					(size 1.016 1.016)
					(thickness 0.1524)
				)
			)
		)
		(property "Device Type" "VIA-PCIE-4P-427097"
			(at -3.4036 -1.9812 0)
			(unlocked yes)
			(layer "F.Fab")
			(hide yes)
			(effects
				(font
					(size 1.016 1.016)
					(thickness 0.1524)
				)
			)
		)
		(duplicate_pad_numbers_are_jumpers no)
		(fp_rect
			(start -2.1336 0.4826)
			(end 2.1336 -0.4826)
			(stroke
				(width 0)
				(type default)
			)
			(fill no)
			(layer "F.CrtYd")
		)
		(fp_rect
			(start -2.1336 0.4826)
			(end 2.1336 -0.4826)
			(stroke
				(width 0)
				(type default)
			)
			(fill no)
			(layer "F.Fab")
		)
		(pad "1" thru_hole circle
			(at -1.651 0)
			(size 0.508 0.508)
			(drill 0.254)
			(layers "*.Cu" "*.Mask")
			(remove_unused_layers no)
			(net "GND")
			(clearance 0.2286)
			(thermal_gap 0.2286)
		)
		(pad "2" thru_hole circle
			(at -0.635 0)
			(size 0.508 0.508)
			(drill 0.254)
			(layers "*.Cu" "*.Mask")
			(remove_unused_layers no)
			(net "PHY_DRV_B_TO_SCC_B_35_DP")
			(clearance 0.2286)
			(thermal_gap 0.2286)
		)
		(pad "3" thru_hole circle
			(at 0.635 0)
			(size 0.508 0.508)
			(drill 0.254)
			(layers "*.Cu" "*.Mask")
			(remove_unused_layers no)
			(net "PHY_DRV_B_TO_SCC_B_35_DN")
			(clearance 0.2286)
			(thermal_gap 0.2286)
		)
		(pad "4" thru_hole circle
			(at 1.651 0)
			(size 0.508 0.508)
			(drill 0.254)
			(layers "*.Cu" "*.Mask")
			(remove_unused_layers no)
			(net "GND")
			(clearance 0.2286)
			(thermal_gap 0.2286)
		)
	)
	(footprint ""
		(layer "F.Cu")
		(at 330.294996 -364.998)
		(property "Reference" "C533"
			(at 0 0 0)
			(layer "F.SilkS")
			(hide yes)
			(effects
				(font
					(size 1.27 1.27)
				)
			)
		)
		(property "Value" "SCD1U25V2KX-2-GP"
			(at 1.1811 -2.7051 0)
			(unlocked yes)
			(layer "F.Fab")
			(hide yes)
			(effects
				(font
					(size 1.016 1.016)
					(thickness 0.1524)
				)
			)
		)
		(property "Device Type" "C402H22"
			(at 1.1811 -4.2291 0)
			(unlocked yes)
			(layer "F.Fab")
			(hide yes)
			(effects
				(font
					(size 1.016 1.016)
					(thickness 0.1524)
				)
			)
		)
		(duplicate_pad_numbers_are_jumpers no)
		(fp_rect
			(start -0.4318 0.9525)
			(end 0.4318 -0.9525)
			(stroke
				(width 0)
				(type default)
			)
			(fill no)
			(layer "F.CrtYd")
		)
		(fp_rect
			(start -0.4318 0.9525)
			(end 0.4318 -0.9525)
			(stroke
				(width 0)
				(type default)
			)
			(fill no)
			(layer "F.Fab")
		)
		(pad "1" smd custom
			(at 0 -0.4445)
			(size 0.1524 0.1524)
			(layers "F.Cu" "F.Mask" "F.Paste")
			(net "FAN_2_TACH1")
			(options
				(clearance outline)
				(anchor circle)
			)
			(primitives
				(gr_poly
					(pts
						(arc
							(start 0.3048 -0.2032)
							(mid 0.275042 -0.275042)
							(end 0.2032 -0.3048)
						)
						(arc
							(start -0.2032 -0.3048)
							(mid -0.275042 -0.275042)
							(end -0.3048 -0.2032)
						)
						(arc
							(start -0.3048 0.2032)
							(mid -0.275042 0.275042)
							(end -0.2032 0.3048)
						)
						(arc
							(start 0.2032 0.3048)
							(mid 0.275042 0.275042)
							(end 0.3048 0.2032)
						)
					)
					(width 0)
					(fill yes)
				)
			)
		)
		(pad "2" smd custom
			(at 0 0.4445)
			(size 0.1524 0.1524)
			(layers "F.Cu" "F.Mask" "F.Paste")
			(net "GND")
			(options
				(clearance outline)
				(anchor circle)
			)
			(primitives
				(gr_poly
					(pts
						(arc
							(start 0.3048 -0.2032)
							(mid 0.275042 -0.275042)
							(end 0.2032 -0.3048)
						)
						(arc
							(start -0.2032 -0.3048)
							(mid -0.275042 -0.275042)
							(end -0.3048 -0.2032)
						)
						(arc
							(start -0.3048 0.2032)
							(mid -0.275042 0.275042)
							(end -0.2032 0.3048)
						)
						(arc
							(start 0.2032 0.3048)
							(mid 0.275042 0.275042)
							(end 0.3048 0.2032)
						)
					)
					(width 0)
					(fill yes)
				)
			)
		)
	)
	(footprint ""
		(layer "F.Cu")
		(at 14.732 -150.622 -90)
		(property "Reference" "C191"
			(at 0 0 270)
			(layer "F.SilkS")
			(hide yes)
			(effects
				(font
					(size 1.27 1.27)
				)
			)
		)
		(property "Value" "SC4D7U25V5KX-1-GP"
			(at -0.0762 -6.1214 270)
			(unlocked yes)
			(layer "F.Fab")
			(hide yes)
			(effects
				(font
					(size 1.016 1.016)
					(thickness 0.1524)
				)
			)
		)
		(property "Device Type" "C805H58"
			(at -0.0762 -8.1534 270)
			(unlocked yes)
			(layer "F.Fab")
			(hide yes)
			(effects
				(font
					(size 1.016 1.016)
					(thickness 0.1524)
				)
			)
		)
		(duplicate_pad_numbers_are_jumpers no)
		(fp_line
			(start 0.635 0)
			(end -0.635 0)
			(stroke
				(width 0.508)
				(type default)
			)
			(layer "F.SilkS")
		)
		(fp_rect
			(start -0.9652 1.778)
			(end 0.9652 -1.778)
			(stroke
				(width 0)
				(type default)
			)
			(fill no)
			(layer "F.CrtYd")
		)
		(fp_poly
			(pts
				(xy -0.9652 -1.778) (xy 0.9652 -1.778) (xy 0.9652 1.778) (xy -0.9652 1.778)
			)
			(stroke
				(width 0)
				(type default)
			)
			(fill no)
			(layer "F.Fab")
		)
		(pad "1" smd rect
			(at 0 -0.9652 270)
			(size 1.397 1.143)
			(layers "F.Cu" "F.Mask" "F.Paste")
			(net "P12V_HDD12")
		)
		(pad "2" smd rect
			(at 0 0.9652 270)
			(size 1.397 1.143)
			(layers "F.Cu" "F.Mask" "F.Paste")
			(net "GND")
		)
	)
)
